# BASEBOARD_FAB2 (Tioga Pass) — schematic netlist excerpt (pin names and nets, part order shuffled) for the footprints in the layout excerpt that follows; sources: Cadence DE-HDL packaged netlist, KiCad conversion of Wiwynn_Tioga_Pass_MB.brd

R3D25  RES  240 1.0% EMPTY  pkg 0402  page 90 : A = GND ; B = PD_CPU1_EAR_N
R9E22  RES  10.0K 1% CHIP  pkg 0402  page 139 : A = PU_JTAG_SPRV_TDO ; B = P3V3_STBY
R9N1  RES  49.9 1% CHIP  pkg 0402  page 55 : A = PVCCIO_CPU1 ; B = SVID_ALERT1_CPU1_R_N

(kicad_pcb
	(version 20260206)
	(generator "pcbnew")
	(generator_version "10.0")
	(general
		(thickness 1.6)
		(legacy_teardrops no)
	)
	(paper "A4")
	(title_block
		(title "Wiwynn_Tioga_Pass_MB.brd")
		(comment 1 "Tioga Pass / footprints 822-824 of 4770")
	)
	(layers
		(0 "F.Cu" signal "TOP")
		(4 "In1.Cu" signal "L2GND")
		(6 "In2.Cu" signal "L3")
		(8 "In3.Cu" signal "L4GND")
		(10 "In4.Cu" signal "L5")
		(12 "In5.Cu" signal "L6GND")
		(14 "In6.Cu" signal "L7VCC")
		(16 "In7.Cu" signal "L8VCC")
		(18 "In8.Cu" signal "L9GND")
		(20 "In9.Cu" signal "L10")
		(22 "In10.Cu" signal "L11GND")
		(24 "In11.Cu" signal "L12")
		(26 "In12.Cu" signal "L13GND")
		(2 "B.Cu" signal "BOTTOM")
		(9 "F.Adhes" user "F.Adhesive")
		(11 "B.Adhes" user "B.Adhesive")
		(13 "F.Paste" user "Package Geometry/Pastemask Top")
		(15 "B.Paste" user "Package Geometry/Pastemask Bottom")
		(5 "F.SilkS" user "Ref Des/Silkscreen Top")
		(7 "B.SilkS" user "Ref Des/Silkscreen Bottom")
		(1 "F.Mask" user "Board Geometry/Soldermask Top")
		(3 "B.Mask" user "Board Geometry/Soldermask Bottom")
		(17 "Dwgs.User" user "User.Drawings")
		(19 "Cmts.User" user "User.Comments")
		(21 "Eco1.User" user "User.Eco1")
		(23 "Eco2.User" user "User.Eco2")
		(25 "Edge.Cuts" user "Board Geometry/Outline")
		(27 "Margin" user)
		(31 "F.CrtYd" user "Package Geometry/Place Bound Top")
		(29 "B.CrtYd" user "Package Geometry/Place Bound Bottom")
		(35 "F.Fab" user "Ref Des/Assembly Top")
		(33 "B.Fab" user "Ref Des/Assembly Bottom")
	)
	(footprint ""
		(layer "F.Cu")
		(at 491.0455 -41.0464 90)
		(property "Reference" "R9E22"
			(at 0 0 90)
			(layer "F.SilkS")
			(hide yes)
			(effects
				(font
					(size 1.27 1.27)
				)
			)
		)
		(property "Value" ""
			(at 0 0 90)
			(layer "F.Fab")
			(effects
				(font
					(size 1.27 1.27)
				)
			)
		)
		(duplicate_pad_numbers_are_jumpers no)
		(fp_poly
			(pts
				(xy -0.2794 -0.1016) (xy 0.2794 -0.1016) (xy 0.2794 0.9906) (xy -0.2794 0.9906)
			)
			(stroke
				(width 0)
				(type default)
			)
			(fill no)
			(layer "F.CrtYd")
		)
		(fp_line
			(start 0.2794 -0.1016)
			(end -0.2794 -0.1016)
			(stroke
				(width 0.1)
				(type default)
			)
			(layer "F.Fab")
		)
		(fp_line
			(start -0.2794 -0.1016)
			(end -0.2794 0.9906)
			(stroke
				(width 0.1)
				(type default)
			)
			(layer "F.Fab")
		)
		(fp_line
			(start 0.2794 0.9906)
			(end 0.2794 -0.1016)
			(stroke
				(width 0.1)
				(type default)
			)
			(layer "F.Fab")
		)
		(fp_line
			(start -0.2794 0.9906)
			(end 0.2794 0.9906)
			(stroke
				(width 0.1)
				(type default)
			)
			(layer "F.Fab")
		)
		(pad "1" smd rect
			(at 0 0 90)
			(size 0.508 0.508)
			(layers "F.Cu" "F.Mask" "F.Paste")
			(net "PU_JTAG_SPRV_TDO")
		)
		(pad "2" smd rect
			(at 0 0.889 90)
			(size 0.508 0.508)
			(layers "F.Cu" "F.Mask" "F.Paste")
			(net "P3V3_STBY")
		)
		(zone
			(layer "F.Cu")
			(hatch none 0.5)
			(connect_pads
				(clearance 0)
			)
			(min_thickness 0.25)
			(keepout
				(tracks allowed)
				(vias not_allowed)
				(pads allowed)
				(copperpour not_allowed)
				(footprints allowed)
			)
			(placement
				(enabled no)
				(sheetname "")
			)
			(fill
				(thermal_gap 0.5)
				(thermal_bridge_width 0.5)
				(island_removal_mode 0)
			)
			(polygon
				(pts
					(xy 491.2995 -40.7924) (xy 491.2995 -41.3004) (xy 491.6805 -41.3004) (xy 491.6805 -40.7924)
				)
			)
		)
		(zone
			(layer "F.Cu")
			(hatch none 0.5)
			(connect_pads
				(clearance 0)
			)
			(min_thickness 0.25)
			(keepout
				(tracks not_allowed)
				(vias allowed)
				(pads allowed)
				(copperpour not_allowed)
				(footprints allowed)
			)
			(placement
				(enabled no)
				(sheetname "")
			)
			(fill
				(thermal_gap 0.5)
				(thermal_bridge_width 0.5)
				(island_removal_mode 0)
			)
			(polygon
				(pts
					(xy 491.6805 -40.7924) (xy 491.6805 -41.3004) (xy 491.2995 -41.3004) (xy 491.2995 -40.7924)
				)
			)
		)
	)
	(footprint ""
		(layer "F.Cu")
		(at 113.1824 -69.4182 90)
		(property "Reference" "R3D25"
			(at 0 0 90)
			(layer "F.SilkS")
			(hide yes)
			(effects
				(font
					(size 1.27 1.27)
				)
			)
		)
		(property "Value" ""
			(at 0 0 90)
			(layer "F.Fab")
			(effects
				(font
					(size 1.27 1.27)
				)
			)
		)
		(duplicate_pad_numbers_are_jumpers no)
		(fp_poly
			(pts
				(xy -0.2794 -0.1016) (xy 0.2794 -0.1016) (xy 0.2794 0.9906) (xy -0.2794 0.9906)
			)
			(stroke
				(width 0)
				(type default)
			)
			(fill no)
			(layer "F.CrtYd")
		)
		(fp_line
			(start 0.2794 -0.1016)
			(end -0.2794 -0.1016)
			(stroke
				(width 0.1)
				(type default)
			)
			(layer "F.Fab")
		)
		(fp_line
			(start -0.2794 -0.1016)
			(end -0.2794 0.9906)
			(stroke
				(width 0.1)
				(type default)
			)
			(layer "F.Fab")
		)
		(fp_line
			(start 0.2794 0.9906)
			(end 0.2794 -0.1016)
			(stroke
				(width 0.1)
				(type default)
			)
			(layer "F.Fab")
		)
		(fp_line
			(start -0.2794 0.9906)
			(end 0.2794 0.9906)
			(stroke
				(width 0.1)
				(type default)
			)
			(layer "F.Fab")
		)
		(pad "1" smd rect
			(at 0 0 90)
			(size 0.508 0.508)
			(layers "F.Cu" "F.Mask" "F.Paste")
			(net "GND")
		)
		(pad "2" smd rect
			(at 0 0.889 90)
			(size 0.508 0.508)
			(layers "F.Cu" "F.Mask" "F.Paste")
			(net "PD_CPU1_EAR_N")
		)
		(zone
			(layer "F.Cu")
			(hatch none 0.5)
			(connect_pads
				(clearance 0)
			)
			(min_thickness 0.25)
			(keepout
				(tracks allowed)
				(vias not_allowed)
				(pads allowed)
				(copperpour not_allowed)
				(footprints allowed)
			)
			(placement
				(enabled no)
				(sheetname "")
			)
			(fill
				(thermal_gap 0.5)
				(thermal_bridge_width 0.5)
				(island_removal_mode 0)
			)
			(polygon
				(pts
					(xy 113.4364 -69.1642) (xy 113.4364 -69.6722) (xy 113.8174 -69.6722) (xy 113.8174 -69.1642)
				)
			)
		)
		(zone
			(layer "F.Cu")
			(hatch none 0.5)
			(connect_pads
				(clearance 0)
			)
			(min_thickness 0.25)
			(keepout
				(tracks not_allowed)
				(vias allowed)
				(pads allowed)
				(copperpour not_allowed)
				(footprints allowed)
			)
			(placement
				(enabled no)
				(sheetname "")
			)
			(fill
				(thermal_gap 0.5)
				(thermal_bridge_width 0.5)
				(island_removal_mode 0)
			)
			(polygon
				(pts
					(xy 113.8174 -69.1642) (xy 113.8174 -69.6722) (xy 113.4364 -69.6722) (xy 113.4364 -69.1642)
				)
			)
		)
	)
	(footprint ""
		(layer "F.Cu")
		(at 39.322756 -107.355132 -90)
		(property "Reference" "R9N1"
			(at 0 0 270)
			(layer "F.SilkS")
			(hide yes)
			(effects
				(font
					(size 1.27 1.27)
				)
			)
		)
		(property "Value" ""
			(at 0 0 270)
			(layer "F.Fab")
			(effects
				(font
					(size 1.27 1.27)
				)
			)
		)
		(duplicate_pad_numbers_are_jumpers no)
		(fp_poly
			(pts
				(xy -0.2794 -0.1016) (xy 0.2794 -0.1016) (xy 0.2794 0.9906) (xy -0.2794 0.9906)
			)
			(stroke
				(width 0)
				(type default)
			)
			(fill no)
			(layer "F.CrtYd")
		)
		(fp_line
			(start -0.2794 0.9906)
			(end 0.2794 0.9906)
			(stroke
				(width 0.1)
				(type default)
			)
			(layer "F.Fab")
		)
		(fp_line
			(start 0.2794 0.9906)
			(end 0.2794 -0.1016)
			(stroke
				(width 0.1)
				(type default)
			)
			(layer "F.Fab")
		)
		(fp_line
			(start -0.2794 -0.1016)
			(end -0.2794 0.9906)
			(stroke
				(width 0.1)
				(type default)
			)
			(layer "F.Fab")
		)
		(fp_line
			(start 0.2794 -0.1016)
			(end -0.2794 -0.1016)
			(stroke
				(width 0.1)
				(type default)
			)
			(layer "F.Fab")
		)
		(pad "1" smd rect
			(at 0 0 270)
			(size 0.508 0.508)
			(layers "F.Cu" "F.Mask" "F.Paste")
			(net "PVCCIO_CPU1")
		)
		(pad "2" smd rect
			(at 0 0.889 270)
			(size 0.508 0.508)
			(layers "F.Cu" "F.Mask" "F.Paste")
			(net "SVID_ALERT1_CPU1_R_N")
		)
		(zone
			(layer "F.Cu")
			(hatch none 0.5)
			(connect_pads
				(clearance 0)
			)
			(min_thickness 0.25)
			(keepout
				(tracks not_allowed)
				(vias allowed)
				(pads allowed)
				(copperpour not_allowed)
				(footprints allowed)
			)
			(placement
				(enabled no)
				(sheetname "")
			)
			(fill
				(thermal_gap 0.5)
				(thermal_bridge_width 0.5)
				(island_removal_mode 0)
			)
			(polygon
				(pts
					(xy 38.687756 -107.609132) (xy 38.687756 -107.101132) (xy 39.068756 -107.101132) (xy 39.068756 -107.609132)
				)
			)
		)
		(zone
			(layer "F.Cu")
			(hatch none 0.5)
			(connect_pads
				(clearance 0)
			)
			(min_thickness 0.25)
			(keepout
				(tracks allowed)
				(vias not_allowed)
				(pads allowed)
				(copperpour not_allowed)
				(footprints allowed)
			)
			(placement
				(enabled no)
				(sheetname "")
			)
			(fill
				(thermal_gap 0.5)
				(thermal_bridge_width 0.5)
				(island_removal_mode 0)
			)
			(polygon
				(pts
					(xy 39.068756 -107.609132) (xy 39.068756 -107.101132) (xy 38.687756 -107.101132) (xy 38.687756 -107.609132)
				)
			)
		)
	)
)
